(kicad_pcb
	(version 20260206)
	(generator "pcbnew")
	(generator_version "10.0")
	(general
		(thickness 1.6)
		(legacy_teardrops no)
	)
	(paper "A4")
	(title_block
		(title "timecard-production-celestica-r4006 — R4006-B0001-02_R01.brd")
		(comment 1 "Time Appliance Project (Time Card) / footprints 296-299 of 1113")
	)
	(layers
		(0 "F.Cu" signal "TOP")
		(4 "In1.Cu" signal "L02_GND1")
		(6 "In2.Cu" signal "L03_SIG1")
		(8 "In3.Cu" signal "L04_GND2")
		(10 "In4.Cu" signal "L05_VCC1")
		(12 "In5.Cu" signal "L06_VCC2")
		(14 "In6.Cu" signal "L07_GND3")
		(16 "In7.Cu" signal "L08_SIG2")
		(18 "In8.Cu" signal "L09_GND4")
		(2 "B.Cu" signal "BOTTOM")
		(9 "F.Adhes" user "F.Adhesive")
		(11 "B.Adhes" user "B.Adhesive")
		(13 "F.Paste" user "Package Geometry/Pastemask Top")
		(15 "B.Paste" user "Package Geometry/Pastemask Bottom")
		(5 "F.SilkS" user "Ref Des/Silkscreen Top")
		(7 "B.SilkS" user "Ref Des/Silkscreen Bottom")
		(1 "F.Mask" user "Board Geometry/Soldermask Top")
		(3 "B.Mask" user "Board Geometry/Soldermask Bottom")
		(17 "Dwgs.User" user "User.Drawings")
		(19 "Cmts.User" user "User.Comments")
		(21 "Eco1.User" user "User.Eco1")
		(23 "Eco2.User" user "User.Eco2")
		(25 "Edge.Cuts" user "Board Geometry/Outline")
		(27 "Margin" user)
		(31 "F.CrtYd" user "Package Geometry/Place Bound Top")
		(29 "B.CrtYd" user "Package Geometry/Place Bound Bottom")
		(35 "F.Fab" user "Ref Des/Assembly Top")
		(33 "B.Fab" user "Ref Des/Assembly Bottom")
	)
	(footprint ""
		(layer "F.Cu")
		(at 90.805 -40.64 90)
		(property "Reference" "C148"
			(at -3.048 -0.59563 90)
			(unlocked yes)
			(layer "F.SilkS")
			(effects
				(font
					(size 0.7874 0.5842)
					(thickness 0.1524)
				)
			)
		)
		(property "Value" "VAL*"
			(at 0.0762 2.067306 90)
			(unlocked yes)
			(layer "F.Fab")
			(hide yes)
			(effects
				(font
					(size 0.7874 0.5842)
					(thickness 0.1524)
				)
			)
		)
		(property "Tolerance" "TOL*"
			(at 0.0762 3.032506 90)
			(unlocked yes)
			(layer "Cmts.User")
			(hide yes)
			(effects
				(font
					(size 0.7874 0.5842)
					(thickness 0.1524)
				)
			)
		)
		(property "User Part Number" "PARTNUM*"
			(at 0.1016 4.023106 90)
			(unlocked yes)
			(layer "Cmts.User")
			(hide yes)
			(effects
				(font
					(size 0.7874 0.5842)
					(thickness 0.1524)
				)
			)
		)
		(property "Device Type" "CAPACITOR-G105-0B104-CK,0.1UF,A"
			(at 0.0508 1.127506 90)
			(unlocked yes)
			(layer "F.Fab")
			(hide yes)
			(effects
				(font
					(size 0.7874 0.5842)
					(thickness 0.1524)
				)
			)
		)
		(duplicate_pad_numbers_are_jumpers no)
		(fp_line
			(start 1.143 -0.5588)
			(end -1.143 -0.5588)
			(stroke
				(width 0.1)
				(type default)
			)
			(layer "F.SilkS")
		)
		(fp_line
			(start -1.143 -0.5588)
			(end -1.143 0.5588)
			(stroke
				(width 0.1)
				(type default)
			)
			(layer "F.SilkS")
		)
		(fp_line
			(start 1.143 0.5588)
			(end 1.143 -0.5588)
			(stroke
				(width 0.1)
				(type default)
			)
			(layer "F.SilkS")
		)
		(fp_line
			(start -1.143 0.5588)
			(end 1.143 0.5588)
			(stroke
				(width 0.1)
				(type default)
			)
			(layer "F.SilkS")
		)
		(fp_rect
			(start -1.143 0.5588)
			(end 1.143 -0.5588)
			(stroke
				(width 0)
				(type default)
			)
			(fill no)
			(layer "F.CrtYd")
		)
		(fp_line
			(start 0.508 -0.3048)
			(end -0.508 -0.3048)
			(stroke
				(width 0.1)
				(type default)
			)
			(layer "F.Fab")
		)
		(fp_line
			(start -0.508 -0.3048)
			(end -0.508 0.3048)
			(stroke
				(width 0.1)
				(type default)
			)
			(layer "F.Fab")
		)
		(fp_line
			(start 0.508 0.3048)
			(end 0.508 -0.3048)
			(stroke
				(width 0.1)
				(type default)
			)
			(layer "F.Fab")
		)
		(fp_line
			(start -0.508 0.3048)
			(end 0.508 0.3048)
			(stroke
				(width 0.1)
				(type default)
			)
			(layer "F.Fab")
		)
		(pad "1" smd rect
			(at -0.5334 0 90)
			(size 0.7112 0.6096)
			(layers "F.Cu" "F.Mask" "F.Paste")
			(net "XP1R0V_FPGA")
		)
		(pad "2" smd rect
			(at 0.5334 0 90)
			(size 0.7112 0.6096)
			(layers "F.Cu" "F.Mask" "F.Paste")
			(net "SG")
		)
		(zone
			(layer "F.Cu")
			(hatch none 0.5)
			(connect_pads
				(clearance 0)
			)
			(min_thickness 0.25)
			(keepout
				(tracks allowed)
				(vias not_allowed)
				(pads allowed)
				(copperpour not_allowed)
				(footprints allowed)
			)
			(placement
				(enabled no)
				(sheetname "")
			)
			(fill
				(thermal_gap 0.5)
				(thermal_bridge_width 0.5)
				(island_removal_mode 0)
			)
			(polygon
				(pts
					(xy 91.1098 -40.5638) (xy 91.1098 -40.7162) (xy 90.5002 -40.7162) (xy 90.5002 -40.5638)
				)
			)
		)
	)
	(footprint ""
		(layer "F.Cu")
		(at 101.219 -24.638 180)
		(property "Reference" "R240"
			(at 10.795 -0.16637 0)
			(unlocked yes)
			(layer "F.SilkS")
			(effects
				(font
					(size 0.7874 0.5842)
					(thickness 0.1524)
				)
			)
		)
		(property "Value" "VAL*"
			(at 0.02032 2.13233 180)
			(unlocked yes)
			(layer "F.Fab")
			(hide yes)
			(effects
				(font
					(size 0.7874 0.5842)
					(thickness 0.1524)
				)
			)
		)
		(property "Tolerance" "TOL*"
			(at 0.044704 3.05435 180)
			(unlocked yes)
			(layer "Cmts.User")
			(hide yes)
			(effects
				(font
					(size 0.7874 0.5842)
					(thickness 0.1524)
				)
			)
		)
		(property "User Part Number" "PARTNUM*"
			(at 0.02032 4.024884 180)
			(unlocked yes)
			(layer "Cmts.User")
			(hide yes)
			(effects
				(font
					(size 0.7874 0.5842)
					(thickness 0.1524)
				)
			)
		)
		(property "Device Type" "RESISTOR-G155-11500-01,150OHM,A"
			(at 0.008382 1.210564 180)
			(unlocked yes)
			(layer "F.Fab")
			(hide yes)
			(effects
				(font
					(size 0.7874 0.5842)
					(thickness 0.1524)
				)
			)
		)
		(duplicate_pad_numbers_are_jumpers no)
		(fp_line
			(start 1.143 0.5588)
			(end 1.143 -0.5588)
			(stroke
				(width 0.1)
				(type default)
			)
			(layer "F.SilkS")
		)
		(fp_line
			(start 1.143 -0.5588)
			(end -1.143 -0.5588)
			(stroke
				(width 0.1)
				(type default)
			)
			(layer "F.SilkS")
		)
		(fp_line
			(start -1.143 0.5588)
			(end 1.143 0.5588)
			(stroke
				(width 0.1)
				(type default)
			)
			(layer "F.SilkS")
		)
		(fp_line
			(start -1.143 -0.5588)
			(end -1.143 0.5588)
			(stroke
				(width 0.1)
				(type default)
			)
			(layer "F.SilkS")
		)
		(fp_rect
			(start 1.143 -0.5588)
			(end -1.143 0.5588)
			(stroke
				(width 0)
				(type default)
			)
			(fill no)
			(layer "F.CrtYd")
		)
		(fp_line
			(start 0.508 0.3048)
			(end 0.508 -0.3048)
			(stroke
				(width 0.1)
				(type default)
			)
			(layer "F.Fab")
		)
		(fp_line
			(start 0.508 -0.3048)
			(end -0.508 -0.3048)
			(stroke
				(width 0.1)
				(type default)
			)
			(layer "F.Fab")
		)
		(fp_line
			(start -0.508 0.3048)
			(end 0.508 0.3048)
			(stroke
				(width 0.1)
				(type default)
			)
			(layer "F.Fab")
		)
		(fp_line
			(start -0.508 -0.3048)
			(end -0.508 0.3048)
			(stroke
				(width 0.1)
				(type default)
			)
			(layer "F.Fab")
		)
		(pad "1" smd rect
			(at -0.5334 0 180)
			(size 0.7112 0.6096)
			(layers "F.Cu" "F.Mask" "F.Paste")
			(net "OSC_125M_CLKN")
		)
		(pad "2" smd rect
			(at 0.5334 0 180)
			(size 0.7112 0.6096)
			(layers "F.Cu" "F.Mask" "F.Paste")
			(net "SG")
		)
		(zone
			(layer "F.Cu")
			(hatch none 0.5)
			(connect_pads
				(clearance 0)
			)
			(min_thickness 0.25)
			(keepout
				(tracks allowed)
				(vias not_allowed)
				(pads allowed)
				(copperpour not_allowed)
				(footprints allowed)
			)
			(placement
				(enabled no)
				(sheetname "")
			)
			(fill
				(thermal_gap 0.5)
				(thermal_bridge_width 0.5)
				(island_removal_mode 0)
			)
			(polygon
				(pts
					(xy 101.1428 -24.3332) (xy 101.2952 -24.3332) (xy 101.2952 -24.9428) (xy 101.1428 -24.9428)
				)
			)
		)
	)
	(footprint ""
		(layer "F.Cu")
		(at 90.017854 -48.653446 90)
		(property "Reference" "U11"
			(at 2.754884 3.581146 0)
			(unlocked yes)
			(layer "F.SilkS")
			(effects
				(font
					(size 0.7874 0.5842)
					(thickness 0.1524)
				)
			)
		)
		(property "Value" ""
			(at 0 0 90)
			(layer "F.Fab")
			(effects
				(font
					(size 1.27 1.27)
				)
			)
		)
		(property "Device Type" "TS3USB3031RMGR_WQFN12-G220-103A"
			(at 0 3.481324 90)
			(unlocked yes)
			(layer "F.Fab")
			(hide yes)
			(effects
				(font
					(size 0.7874 0.5842)
					(thickness 0.1524)
				)
			)
		)
		(property "User Part Number" "PARTNUM*"
			(at 0 4.675124 90)
			(unlocked yes)
			(layer "Cmts.User")
			(hide yes)
			(effects
				(font
					(size 0.7874 0.5842)
					(thickness 0.1524)
				)
			)
		)
		(duplicate_pad_numbers_are_jumpers no)
		(fp_line
			(start 1.690624 -1.690624)
			(end -1.690624 -1.690624)
			(stroke
				(width 0.1)
				(type default)
			)
			(layer "F.SilkS")
		)
		(fp_line
			(start -1.690624 -1.690624)
			(end -1.690624 1.690624)
			(stroke
				(width 0.1)
				(type default)
			)
			(layer "F.SilkS")
		)
		(fp_line
			(start 1.690624 1.690624)
			(end 1.690624 -1.690624)
			(stroke
				(width 0.1)
				(type default)
			)
			(layer "F.SilkS")
		)
		(fp_line
			(start -1.690624 1.690624)
			(end 1.690624 1.690624)
			(stroke
				(width 0.1)
				(type default)
			)
			(layer "F.SilkS")
		)
		(fp_poly
			(pts
				(arc
					(start -2.368296 -0.184658)
					(mid -2.368296 -0.946658)
					(end -2.368296 -0.184658)
				)
			)
			(stroke
				(width 0)
				(type default)
			)
			(fill yes)
			(layer "F.SilkS")
		)
		(fp_rect
			(start -1.944624 -1.944624)
			(end 1.944624 1.944624)
			(stroke
				(width 0)
				(type default)
			)
			(fill no)
			(layer "F.CrtYd")
		)
		(fp_line
			(start 0.94996 -0.94996)
			(end -0.94996 -0.94996)
			(stroke
				(width 0.1)
				(type default)
			)
			(layer "F.Fab")
		)
		(fp_line
			(start -0.94996 -0.94996)
			(end -0.94996 0.94996)
			(stroke
				(width 0.1)
				(type default)
			)
			(layer "F.Fab")
		)
		(fp_line
			(start 0.94996 0.94996)
			(end 0.94996 -0.94996)
			(stroke
				(width 0.1)
				(type default)
			)
			(layer "F.Fab")
		)
		(fp_line
			(start -0.94996 0.94996)
			(end 0.94996 0.94996)
			(stroke
				(width 0.1)
				(type default)
			)
			(layer "F.Fab")
		)
		(fp_poly
			(pts
				(arc
					(start -1.733296 -0.438658)
					(mid -1.733296 -1.200658)
					(end -1.733296 -0.438658)
				)
			)
			(stroke
				(width 0)
				(type default)
			)
			(fill yes)
			(layer "F.Fab")
		)
		(fp_text user "8"
			(at 2.1844 -0.455168 90)
			(unlocked yes)
			(layer "F.SilkS")
			(effects
				(font
					(size 0.635 0.4064)
					(thickness 0.1524)
				)
			)
		)
		(fp_text user "2"
			(at -2.203196 0.533146 0)
			(unlocked yes)
			(layer "F.SilkS")
			(effects
				(font
					(size 0.635 0.4064)
					(thickness 0.1524)
				)
			)
		)
		(fp_text user "7"
			(at 2.207006 0.53848 90)
			(unlocked yes)
			(layer "F.SilkS")
			(effects
				(font
					(size 0.635 0.4064)
					(thickness 0.1524)
				)
			)
		)
		(fp_text user "3"
			(at -1.390396 2.057146 0)
			(unlocked yes)
			(layer "F.SilkS")
			(effects
				(font
					(size 0.635 0.4064)
					(thickness 0.1524)
				)
			)
		)
		(fp_text user "6"
			(at 1.479804 2.692146 0)
			(unlocked yes)
			(layer "F.SilkS")
			(effects
				(font
					(size 0.635 0.4064)
					(thickness 0.1524)
				)
			)
		)
		(fp_text user "12"
			(at -0.674116 -2.006854 0)
			(unlocked yes)
			(layer "F.Fab")
			(effects
				(font
					(size 0.7874 0.5842)
					(thickness 0.1524)
				)
			)
		)
		(fp_text user "9"
			(at 0.722884 -1.752854 0)
			(unlocked yes)
			(layer "F.Fab")
			(effects
				(font
					(size 0.7874 0.5842)
					(thickness 0.1524)
				)
			)
		)
		(fp_text user "8"
			(at 1.77673 -0.677418 0)
			(unlocked yes)
			(layer "F.Fab")
			(effects
				(font
					(size 0.7874 0.5842)
					(thickness 0.1524)
				)
			)
		)
		(fp_text user "7"
			(at 1.798828 0.316484 0)
			(unlocked yes)
			(layer "F.Fab")
			(effects
				(font
					(size 0.7874 0.5842)
					(thickness 0.1524)
				)
			)
		)
		(fp_text user "2"
			(at -1.563116 0.914146 0)
			(unlocked yes)
			(layer "F.Fab")
			(effects
				(font
					(size 0.7874 0.5842)
					(thickness 0.1524)
				)
			)
		)
		(fp_text user "6"
			(at 1.103884 1.549146 0)
			(unlocked yes)
			(layer "F.Fab")
			(effects
				(font
					(size 0.7874 0.5842)
					(thickness 0.1524)
				)
			)
		)
		(fp_text user "3"
			(at -0.420116 1.549146 0)
			(unlocked yes)
			(layer "F.Fab")
			(effects
				(font
					(size 0.7874 0.5842)
					(thickness 0.1524)
				)
			)
		)
		(pad "1" smd rect
			(at -0.763524 -0.199898 90)
			(size 1.3462 0.2032)
			(layers "F.Cu" "F.Mask" "F.Paste")
			(net "XP5R0V_USB_CONN_DET")
		)
		(pad "2" smd rect
			(at -0.763524 0.200152 90)
			(size 1.3462 0.2032)
			(layers "F.Cu" "F.Mask" "F.Paste")
			(net "UNNAMED_527_RESISTOR_I126_1")
		)
		(pad "3" smd rect
			(at -0.599948 0.966724 90)
			(size 0.2032 0.9398)
			(layers "F.Cu" "F.Mask" "F.Paste")
			(net "MAC_USB_DP")
		)
		(pad "4" smd rect
			(at -0.199898 0.966724 90)
			(size 0.2032 0.9398)
			(layers "F.Cu" "F.Mask" "F.Paste")
			(net "MAC_USB_DM")
		)
		(pad "5" smd rect
			(at 0.199898 0.966724 90)
			(size 0.2032 0.9398)
			(layers "F.Cu" "F.Mask" "F.Paste")
			(net "CONN_MICRO_USB_DP")
		)
		(pad "6" smd rect
			(at 0.599948 0.966724 90)
			(size 0.2032 0.9398)
			(layers "F.Cu" "F.Mask" "F.Paste")
			(net "CONN_MICRO_USB_DM")
		)
		(pad "7" smd rect
			(at 0.763524 0.200152 90)
			(size 1.3462 0.2032)
			(layers "F.Cu" "F.Mask" "F.Paste")
			(net "Net_759")
		)
		(pad "8" smd rect
			(at 0.763524 -0.199898 90)
			(size 1.3462 0.2032)
			(layers "F.Cu" "F.Mask" "F.Paste")
			(net "Net_760")
		)
		(pad "9" smd rect
			(at 0.599948 -0.966724 90)
			(size 0.2032 0.9398)
			(layers "F.Cu" "F.Mask" "F.Paste")
			(net "SG")
		)
		(pad "10" smd rect
			(at 0.199898 -0.966724 90)
			(size 0.2032 0.9398)
			(layers "F.Cu" "F.Mask" "F.Paste")
			(net "MUX_USB_DM")
		)
		(pad "11" smd rect
			(at -0.199898 -0.966724 90)
			(size 0.2032 0.9398)
			(layers "F.Cu" "F.Mask" "F.Paste")
			(net "MUX_USB_DP")
		)
		(pad "12" smd rect
			(at -0.599948 -0.966724 90)
			(size 0.2032 0.9398)
			(layers "F.Cu" "F.Mask" "F.Paste")
			(net "XP3R3V_FPGA")
		)
	)
	(footprint ""
		(layer "F.Cu")
		(at 133.4516 -94.107 90)
		(property "Reference" "C10"
			(at -2.921 0.44577 90)
			(unlocked yes)
			(layer "F.SilkS")
			(effects
				(font
					(size 0.7874 0.5842)
					(thickness 0.1524)
				)
			)
		)
		(property "Value" "VAL*"
			(at 0.0762 3.134106 90)
			(unlocked yes)
			(layer "F.Fab")
			(hide yes)
			(effects
				(font
					(size 0.7874 0.5842)
					(thickness 0.1524)
				)
			)
		)
		(property "Device Type" "CAPACITOR-G107-0F106-EM,10UF,2A"
			(at 0.0508 2.194306 90)
			(unlocked yes)
			(layer "F.Fab")
			(hide yes)
			(effects
				(font
					(size 0.7874 0.5842)
					(thickness 0.1524)
				)
			)
		)
		(property "User Part Number" "PARTNUM*"
			(at 0.1016 5.013706 90)
			(unlocked yes)
			(layer "Cmts.User")
			(hide yes)
			(effects
				(font
					(size 0.7874 0.5842)
					(thickness 0.1524)
				)
			)
		)
		(property "Tolerance" "TOL*"
			(at 0.0762 4.048506 90)
			(unlocked yes)
			(layer "Cmts.User")
			(hide yes)
			(effects
				(font
					(size 0.7874 0.5842)
					(thickness 0.1524)
				)
			)
		)
		(duplicate_pad_numbers_are_jumpers no)
		(fp_line
			(start 1.5748 -0.9398)
			(end -1.5748 -0.9398)
			(stroke
				(width 0.1)
				(type default)
			)
			(layer "F.SilkS")
		)
		(fp_line
			(start -1.5748 -0.9398)
			(end -1.5748 0.9398)
			(stroke
				(width 0.1)
				(type default)
			)
			(layer "F.SilkS")
		)
		(fp_line
			(start 1.5748 0.9398)
			(end 1.5748 -0.9398)
			(stroke
				(width 0.1)
				(type default)
			)
			(layer "F.SilkS")
		)
		(fp_line
			(start -1.5748 0.9398)
			(end 1.5748 0.9398)
			(stroke
				(width 0.1)
				(type default)
			)
			(layer "F.SilkS")
		)
		(fp_rect
			(start -1.5748 -0.9398)
			(end 1.5748 0.9398)
			(stroke
				(width 0)
				(type default)
			)
			(fill no)
			(layer "F.CrtYd")
		)
		(fp_line
			(start 1.016 -0.635)
			(end -1.016 -0.635)
			(stroke
				(width 0.1)
				(type default)
			)
			(layer "F.Fab")
		)
		(fp_line
			(start -1.016 -0.635)
			(end -1.016 0.635)
			(stroke
				(width 0.1)
				(type default)
			)
			(layer "F.Fab")
		)
		(fp_line
			(start 1.016 0.635)
			(end 1.016 -0.635)
			(stroke
				(width 0.1)
				(type default)
			)
			(layer "F.Fab")
		)
		(fp_line
			(start -1.016 0.635)
			(end 1.016 0.635)
			(stroke
				(width 0.1)
				(type default)
			)
			(layer "F.Fab")
		)
		(pad "1" smd rect
			(at -0.8382 0 90)
			(size 0.9652 1.3716)
			(layers "F.Cu" "F.Mask" "F.Paste")
			(net "XP12R0V")
		)
		(pad "2" smd rect
			(at 0.8382 0 90)
			(size 0.9652 1.3716)
			(layers "F.Cu" "F.Mask" "F.Paste")
			(net "SG")
		)
		(zone
			(layer "F.Cu")
			(hatch none 0.5)
			(connect_pads
				(clearance 0)
			)
			(min_thickness 0.25)
			(keepout
				(tracks allowed)
				(vias not_allowed)
				(pads allowed)
				(copperpour not_allowed)
				(footprints allowed)
			)
			(placement
				(enabled no)
				(sheetname "")
			)
			(fill
				(thermal_gap 0.5)
				(thermal_bridge_width 0.5)
				(island_removal_mode 0)
			)
			(polygon
				(pts
					(xy 132.8166 -93.8784) (xy 134.0866 -93.8784) (xy 134.0866 -94.3356) (xy 132.8166 -94.3356)
				)
			)
		)
	)
)
